# BASEBOARD_FAB2 (Tioga Pass) — schematic netlist excerpt (pin names and nets, part order shuffled) for the footprints in the layout excerpt that follows; sources: Cadence DE-HDL packaged netlist, KiCad conversion of Wiwynn_Tioga_Pass_MB.brd

J1G3  SCONN288_H44441004  SCONN  pkg PIP  page 81
  \12v\(1)  = P12V_NVDIMM_GHJ
  VSS(93)  = GND
  DQ(4)  = M_J_DQ<5>
  VSS(92)  = GND
  DQ(0)  = M_J_DQ<1>
  VSS(91)  = GND
  DQS9P  = M_J_DQS_DP<9>
  DQS9N  = M_J_DQS_DN<9>
  VSS(90)  = GND
  DQ(6)  = M_J_DQ<7>
  VSS(89)  = GND
  DQ(2)  = M_J_DQ<3>
  VSS(88)  = GND
  DQ(12)  = M_J_DQ<13>
  VSS(87)  = GND
  DQ(8)  = M_J_DQ<9>
  VSS(86)  = GND
  DQS10P  = M_J_DQS_DP<10>
  DQS10N  = M_J_DQS_DN<10>
  VSS(85)  = GND
  DQ(14)  = M_J_DQ<15>
  VSS(84)  = GND
  DQ(10)  = M_J_DQ<11>
  VSS(83)  = GND
  DQ(20)  = M_J_DQ<21>
  VSS(82)  = GND
  DQ(16)  = M_J_DQ<17>
  VSS(81)  = GND
  DQS11P  = M_J_DQS_DP<11>
  DQS11N  = M_J_DQS_DN<11>
  VSS(80)  = GND
  DQ(22)  = M_J_DQ<23>
  VSS(79)  = GND
  DQ(18)  = M_J_DQ<19>
  VSS(78)  = GND
  DQ(28)  = M_J_DQ<29>
  VSS(77)  = GND
  DQ(24)  = M_J_DQ<25>
  VSS(76)  = GND
  DQS12P  = M_J_DQS_DP<12>
  DQS12N  = M_J_DQS_DN<12>
  VSS(75)  = GND
  DQ(30)  = M_J_DQ<31>
  VSS(74)  = GND
  DQ(26)  = M_J_DQ<27>
  VSS(73)  = GND
  CB(4)  = M_J_ECC<5>
  VSS(72)  = GND
  CB(0)  = M_J_ECC<1>
  VSS(71)  = GND
  DQS17P  = M_J_DQS_DP<17>
  DQS17N  = M_J_DQS_DN<17>
  VSS(70)  = GND
  CB(6)  = M_J_ECC<7>
  VSS(69)  = GND
  CB(2)  = M_J_ECC<3>
  VSS(68)  = GND
  RESET_N  = M_GHJ_RST_N
  VDD(25)  = PVDDQ_GHJ
  CKE(0)  = M_J_CKE<0>
  VDD(24)  = PVDDQ_GHJ
  ACT_N  = M_J_ACT_N
  BG(0)  = M_J_BG<0>
  VDD(23)  = PVDDQ_GHJ
  A12  = M_J_MA<12>
  A9  = M_J_MA<9>
  VDD(22)  = PVDDQ_GHJ
  A8  = M_J_MA<8>
  A6  = M_J_MA<6>
  VDD(21)  = PVDDQ_GHJ
  A3  = M_J_MA<3>
  A1  = M_J_MA<1>
  VDD(20)  = PVDDQ_GHJ
  CK0P  = M_J_CLK_DP<0>
  CK0N  = M_J_CLK_DN<0>
  VDD(19)  = PVDDQ_GHJ
  VTT(1)  = PVTT_GHJ
  EVENT_N  = FM_DIMM_EVENT_COD_N
  A0  = M_J_MA<0>
  VDD(18)  = PVDDQ_GHJ
  BA(0)  = M_J_BA<0>
  A16_RAS_N  = M_J_MA<16>
  VDD(17)  = PVDDQ_GHJ
  S0_N  = M_J_CS_N<0>
  VDD(16)  = PVDDQ_GHJ
  A15_CAS_N  = M_J_MA<15>
  ODT(0)  = M_J_ODT<0>
  VDD(15)  = PVDDQ_GHJ
  S1_N  = M_J_CS_N<1>
  VDD(14)  = PVDDQ_GHJ
  ODT(1)  = M_J_ODT<1>
  VDD(13)  = PVDDQ_GHJ
  S2_N_C(0)  = M_J_CS_N<2>
  VSS(67)  = GND
  DQ(36)  = M_J_DQ<37>
  VSS(66)  = GND
  DQ(32)  = M_J_DQ<33>
  VSS(65)  = GND
  DQS13P  = M_J_DQS_DP<13>
  DQS13N  = M_J_DQS_DN<13>
  VSS(64)  = GND
  DQ(38)  = M_J_DQ<39>
  VSS(63)  = GND
  DQ(34)  = M_J_DQ<35>
  VSS(62)  = GND
  DQ(44)  = M_J_DQ<45>
  VSS(61)  = GND
  DQ(40)  = M_J_DQ<41>
  VSS(60)  = GND
  DQS14P  = M_J_DQS_DP<14>
  DQS14N  = M_J_DQS_DN<14>
  VSS(59)  = GND
  DQ(46)  = M_J_DQ<47>
  VSS(58)  = GND
  DQ(42)  = M_J_DQ<43>
  VSS(57)  = GND
  DQ(52)  = M_J_DQ<53>
  VSS(56)  = GND
  DQ(48)  = M_J_DQ<49>
  VSS(55)  = GND
  DQS15P  = M_J_DQS_DP<15>
  DQS15N  = M_J_DQS_DN<15>
  VSS(54)  = GND
  DQ(54)  = M_J_DQ<55>
  VSS(53)  = GND
  DQ(50)  = M_J_DQ<51>
  VSS(52)  = GND
  DQ(60)  = M_J_DQ<61>
  VSS(51)  = GND
  DQ(56)  = M_J_DQ<57>
  VSS(50)  = GND
  DQS16P  = M_J_DQS_DP<16>
  DQS16N  = M_J_DQS_DN<16>
  VSS(49)  = GND
  DQ(62)  = M_J_DQ<63>
  VSS(48)  = GND
  DQ(58)  = M_J_DQ<59>
  VSS(47)  = GND
  SA(0)  = GND
  SA(1)  = GND
  SCL  = SMB_DDR_GHJ_VPP_SCL
  VPP(4)  = PVPP_GHJ
  VPP(3)  = PVPP_GHJ
  RFU(2)  = TP_CH_J_DIMM_J0_RFU_2
  \12v\(0)  = P12V_NVDIMM_GHJ
  VREFCA  = M_J_VREF
  VSS(46)  = GND
  DQ(5)  = M_J_DQ<4>
  VSS(45)  = GND
  DQ(1)  = M_J_DQ<0>
  VSS(44)  = GND
  DQS0N  = M_J_DQS_DN<0>
  DQS0P  = M_J_DQS_DP<0>
  VSS(43)  = GND
  DQ(7)  = M_J_DQ<6>
  VSS(42)  = GND
  DQ(3)  = M_J_DQ<2>
  VSS(41)  = GND
  DQ(13)  = M_J_DQ<12>
  VSS(40)  = GND
  DQ(9)  = M_J_DQ<8>
  VSS(39)  = GND
  DQS1N  = M_J_DQS_DN<1>
  DQS1P  = M_J_DQS_DP<1>
  VSS(38)  = GND
  DQ(15)  = M_J_DQ<14>
  VSS(37)  = GND
  DQ(11)  = M_J_DQ<10>
  VSS(36)  = GND
  DQ(21)  = M_J_DQ<20>
  VSS(35)  = GND
  DQ(17)  = M_J_DQ<16>
  VSS(34)  = GND
  DQS2N  = M_J_DQS_DN<2>
  DQS2P  = M_J_DQS_DP<2>
  VSS(33)  = GND
  DQ(23)  = M_J_DQ<22>
  VSS(32)  = GND
  DQ(19)  = M_J_DQ<18>
  VSS(31)  = GND
  DQ(29)  = M_J_DQ<28>
  VSS(30)  = GND
  DQ(25)  = M_J_DQ<24>
  VSS(29)  = GND
  DQS3N  = M_J_DQS_DN<3>
  DQS3P  = M_J_DQS_DP<3>
  VSS(28)  = GND
  DQ(31)  = M_J_DQ<30>
  VSS(27)  = GND
  DQ(27)  = M_J_DQ<26>
  VSS(26)  = GND
  CB(5)  = M_J_ECC<4>
  VSS(25)  = GND
  CB(1)  = M_J_ECC<0>
  VSS(24)  = GND
  DQS8N  = M_J_DQS_DN<8>
  DQS8P  = M_J_DQS_DP<8>
  VSS(23)  = GND
  CB(7)  = M_J_ECC<6>
  VSS(22)  = GND
  CB(3)  = M_J_ECC<2>
  VSS(21)  = GND
  CKE(1)  = M_J_CKE<1>
  VDD(12)  = PVDDQ_GHJ
  RFU(0)  = TP_CH_J_DIMM_J0_RFU_0
  VDD(11)  = PVDDQ_GHJ
  BG(1)  = M_J_BG<1>
  ALERT_N  = M_J_ALERT_N
  VDD(10)  = PVDDQ_GHJ
  A11  = M_J_MA<11>
  A7  = M_J_MA<7>
  VDD(9)  = PVDDQ_GHJ
  A5  = M_J_MA<5>
  A4  = M_J_MA<4>
  VDD(8)  = PVDDQ_GHJ
  A2  = M_J_MA<2>
  VDD(7)  = PVDDQ_GHJ
  CK1P  = M_J_CLK_DP<1>
  CK1N  = M_J_CLK_DN<1>
  VDD(6)  = PVDDQ_GHJ
  VTT(0)  = PVTT_GHJ
  PAR  = M_J_PAR
  VDD(5)  = PVDDQ_GHJ
  BA(1)  = M_J_BA<1>
  A10  = M_J_MA<10>
  VDD(4)  = PVDDQ_GHJ
  RFU(1)  = TP_CH_J_DIMM_J0_RFU_1
  A14_WE_N  = M_J_MA<14>
  VDD(3)  = PVDDQ_GHJ
  SAVE_N_NC  = FM_ADR_COMPLETE_GHJ_N
  VDD(2)  = PVDDQ_GHJ
  A13  = M_J_MA<13>
  VDD(1)  = PVDDQ_GHJ
  A17  = M_J_MA<17>
  C(2)  = M_J_C<2>
  VDD(0)  = PVDDQ_GHJ
  S3_N_C(1)  = M_J_CS_N<3>
  SA(2)  = PVPP_GHJ
  VSS(20)  = GND
  DQ(37)  = M_J_DQ<36>
  VSS(19)  = GND
  DQ(33)  = M_J_DQ<32>
  VSS(18)  = GND
  DQS4N  = M_J_DQS_DN<4>
  DQS4P  = M_J_DQS_DP<4>
  VSS(17)  = GND
  DQ(39)  = M_J_DQ<38>
  VSS(16)  = GND
  DQ(35)  = M_J_DQ<34>
  VSS(15)  = GND
  DQ(45)  = M_J_DQ<44>
  VSS(14)  = GND
  DQ(41)  = M_J_DQ<40>
  VSS(13)  = GND
  DQS5N  = M_J_DQS_DN<5>
  DQS5P  = M_J_DQS_DP<5>
  VSS(12)  = GND
  DQ(47)  = M_J_DQ<46>
  VSS(11)  = GND
  DQ(43)  = M_J_DQ<42>
  VSS(10)  = GND
  DQ(53)  = M_J_DQ<52>
  VSS(9)  = GND
  DQ(49)  = M_J_DQ<48>
  VSS(8)  = GND
  DQS6N  = M_J_DQS_DN<6>
  DQS6P  = M_J_DQS_DP<6>
  VSS(7)  = GND
  DQ(55)  = M_J_DQ<54>
  VSS(6)  = GND
  DQ(51)  = M_J_DQ<50>
  VSS(5)  = GND
  DQ(61)  = M_J_DQ<60>
  VSS(4)  = GND
  DQ(57)  = M_J_DQ<56>
  VSS(3)  = GND
  DQS7N  = M_J_DQS_DN<7>
  DQS7P  = M_J_DQS_DP<7>
  VSS(2)  = GND
  DQ(63)  = M_J_DQ<62>
  VSS(1)  = GND
  DQ(59)  = M_J_DQ<58>
  VSS(0)  = GND
  VDDSPD  = PVPP_GHJ
  SDA  = SMB_DDR_GHJ_VPP_SDA
  VPP(1)  = PVPP_GHJ
  VPP(0)  = PVPP_GHJ
  VPP(2)  = PVPP_GHJ

(kicad_pcb
	(version 20260206)
	(generator "pcbnew")
	(generator_version "10.0")
	(general
		(thickness 1.6)
		(legacy_teardrops no)
	)
	(paper "A4")
	(title_block
		(title "Wiwynn_Tioga_Pass_MB.brd")
		(comment 1 "Tioga Pass / footprint 437 of 4770 (J1G3), pads 251-291 of 291")
	)
	(layers
		(0 "F.Cu" signal "TOP")
		(4 "In1.Cu" signal "L2GND")
		(6 "In2.Cu" signal "L3")
		(8 "In3.Cu" signal "L4GND")
		(10 "In4.Cu" signal "L5")
		(12 "In5.Cu" signal "L6GND")
		(14 "In6.Cu" signal "L7VCC")
		(16 "In7.Cu" signal "L8VCC")
		(18 "In8.Cu" signal "L9GND")
		(20 "In9.Cu" signal "L10")
		(22 "In10.Cu" signal "L11GND")
		(24 "In11.Cu" signal "L12")
		(26 "In12.Cu" signal "L13GND")
		(2 "B.Cu" signal "BOTTOM")
		(9 "F.Adhes" user "F.Adhesive")
		(11 "B.Adhes" user "B.Adhesive")
		(13 "F.Paste" user "Package Geometry/Pastemask Top")
		(15 "B.Paste" user "Package Geometry/Pastemask Bottom")
		(5 "F.SilkS" user "Ref Des/Silkscreen Top")
		(7 "B.SilkS" user "Ref Des/Silkscreen Bottom")
		(1 "F.Mask" user "Board Geometry/Soldermask Top")
		(3 "B.Mask" user "Board Geometry/Soldermask Bottom")
		(17 "Dwgs.User" user "User.Drawings")
		(19 "Cmts.User" user "User.Comments")
		(21 "Eco1.User" user "User.Eco1")
		(23 "Eco2.User" user "User.Eco2")
		(25 "Edge.Cuts" user "Board Geometry/Outline")
		(27 "Margin" user)
		(31 "F.CrtYd" user "Package Geometry/Place Bound Top")
		(29 "B.CrtYd" user "Package Geometry/Place Bound Bottom")
		(35 "F.Fab" user "Ref Des/Assembly Top")
		(33 "B.Fab" user "Ref Des/Assembly Bottom")
	)
	(footprint ""
		(layer "F.Cu")
		(at 29.699458 3.778758 90)
		(property "Reference" "J1G3"
			(at 7.054088 34.562542 0)
			(unlocked yes)
			(layer "F.SilkS")
			(effects
				(font
					(size 0.7874 0.5842)
					(thickness 0.1524)
				)
				(justify left)
			)
		)
		(property "Value" ""
			(at 0 0 90)
			(layer "F.Fab")
			(effects
				(font
					(size 1.27 1.27)
				)
			)
		)
		(duplicate_pad_numbers_are_jumpers no)
		(pad "248" smd rect
			(at 4.59994 92.650056 90)
			(size 1.8034 0.508)
			(layers "F.Cu" "F.Mask" "F.Paste")
			(net "GND")
		)
		(pad "249" smd rect
			(at 4.59994 93.49994 90)
			(size 1.8034 0.508)
			(layers "F.Cu" "F.Mask" "F.Paste")
			(net "M_J_DQ<34>")
		)
		(pad "250" smd rect
			(at 4.59994 94.350078 90)
			(size 1.8034 0.508)
			(layers "F.Cu" "F.Mask" "F.Paste")
			(net "GND")
		)
		(pad "251" smd rect
			(at 4.59994 95.199962 90)
			(size 1.8034 0.508)
			(layers "F.Cu" "F.Mask" "F.Paste")
			(net "M_J_DQ<44>")
		)
		(pad "252" smd rect
			(at 4.59994 96.0501 90)
			(size 1.8034 0.508)
			(layers "F.Cu" "F.Mask" "F.Paste")
			(net "GND")
		)
		(pad "253" smd rect
			(at 4.59994 96.899984 90)
			(size 1.8034 0.508)
			(layers "F.Cu" "F.Mask" "F.Paste")
			(net "M_J_DQ<40>")
		)
		(pad "254" smd rect
			(at 4.59994 97.750122 90)
			(size 1.8034 0.508)
			(layers "F.Cu" "F.Mask" "F.Paste")
			(net "GND")
		)
		(pad "255" smd rect
			(at 4.59994 98.600006 90)
			(size 1.8034 0.508)
			(layers "F.Cu" "F.Mask" "F.Paste")
			(net "M_J_DQS_DN<5>")
		)
		(pad "256" smd rect
			(at 4.59994 99.44989 90)
			(size 1.8034 0.508)
			(layers "F.Cu" "F.Mask" "F.Paste")
			(net "M_J_DQS_DP<5>")
		)
		(pad "257" smd rect
			(at 4.59994 100.300028 90)
			(size 1.8034 0.508)
			(layers "F.Cu" "F.Mask" "F.Paste")
			(net "GND")
		)
		(pad "258" smd rect
			(at 4.59994 101.149912 90)
			(size 1.8034 0.508)
			(layers "F.Cu" "F.Mask" "F.Paste")
			(net "M_J_DQ<46>")
		)
		(pad "259" smd rect
			(at 4.59994 102.00005 90)
			(size 1.8034 0.508)
			(layers "F.Cu" "F.Mask" "F.Paste")
			(net "GND")
		)
		(pad "260" smd rect
			(at 4.59994 102.849934 90)
			(size 1.8034 0.508)
			(layers "F.Cu" "F.Mask" "F.Paste")
			(net "M_J_DQ<42>")
		)
		(pad "261" smd rect
			(at 4.59994 103.700072 90)
			(size 1.8034 0.508)
			(layers "F.Cu" "F.Mask" "F.Paste")
			(net "GND")
		)
		(pad "262" smd rect
			(at 4.59994 104.549956 90)
			(size 1.8034 0.508)
			(layers "F.Cu" "F.Mask" "F.Paste")
			(net "M_J_DQ<52>")
		)
		(pad "263" smd rect
			(at 4.59994 105.400094 90)
			(size 1.8034 0.508)
			(layers "F.Cu" "F.Mask" "F.Paste")
			(net "GND")
		)
		(pad "264" smd rect
			(at 4.59994 106.249978 90)
			(size 1.8034 0.508)
			(layers "F.Cu" "F.Mask" "F.Paste")
			(net "M_J_DQ<48>")
		)
		(pad "265" smd rect
			(at 4.59994 107.100116 90)
			(size 1.8034 0.508)
			(layers "F.Cu" "F.Mask" "F.Paste")
			(net "GND")
		)
		(pad "266" smd rect
			(at 4.59994 107.95 90)
			(size 1.8034 0.508)
			(layers "F.Cu" "F.Mask" "F.Paste")
			(net "M_J_DQS_DN<6>")
		)
		(pad "267" smd rect
			(at 4.59994 108.799884 90)
			(size 1.8034 0.508)
			(layers "F.Cu" "F.Mask" "F.Paste")
			(net "M_J_DQS_DP<6>")
		)
		(pad "268" smd rect
			(at 4.59994 109.650022 90)
			(size 1.8034 0.508)
			(layers "F.Cu" "F.Mask" "F.Paste")
			(net "GND")
		)
		(pad "269" smd rect
			(at 4.59994 110.499906 90)
			(size 1.8034 0.508)
			(layers "F.Cu" "F.Mask" "F.Paste")
			(net "M_J_DQ<54>")
		)
		(pad "270" smd rect
			(at 4.59994 111.350044 90)
			(size 1.8034 0.508)
			(layers "F.Cu" "F.Mask" "F.Paste")
			(net "GND")
		)
		(pad "271" smd rect
			(at 4.59994 112.199928 90)
			(size 1.8034 0.508)
			(layers "F.Cu" "F.Mask" "F.Paste")
			(net "M_J_DQ<50>")
		)
		(pad "272" smd rect
			(at 4.59994 113.050066 90)
			(size 1.8034 0.508)
			(layers "F.Cu" "F.Mask" "F.Paste")
			(net "GND")
		)
		(pad "273" smd rect
			(at 4.59994 113.89995 90)
			(size 1.8034 0.508)
			(layers "F.Cu" "F.Mask" "F.Paste")
			(net "M_J_DQ<60>")
		)
		(pad "274" smd rect
			(at 4.59994 114.750088 90)
			(size 1.8034 0.508)
			(layers "F.Cu" "F.Mask" "F.Paste")
			(net "GND")
		)
		(pad "275" smd rect
			(at 4.59994 115.599972 90)
			(size 1.8034 0.508)
			(layers "F.Cu" "F.Mask" "F.Paste")
			(net "M_J_DQ<56>")
		)
		(pad "276" smd rect
			(at 4.59994 116.45011 90)
			(size 1.8034 0.508)
			(layers "F.Cu" "F.Mask" "F.Paste")
			(net "GND")
		)
		(pad "277" smd rect
			(at 4.59994 117.299994 90)
			(size 1.8034 0.508)
			(layers "F.Cu" "F.Mask" "F.Paste")
			(net "M_J_DQS_DN<7>")
		)
		(pad "278" smd rect
			(at 4.59994 118.149878 90)
			(size 1.8034 0.508)
			(layers "F.Cu" "F.Mask" "F.Paste")
			(net "M_J_DQS_DP<7>")
		)
		(pad "279" smd rect
			(at 4.59994 119.000016 90)
			(size 1.8034 0.508)
			(layers "F.Cu" "F.Mask" "F.Paste")
			(net "GND")
		)
		(pad "280" smd rect
			(at 4.59994 119.8499 90)
			(size 1.8034 0.508)
			(layers "F.Cu" "F.Mask" "F.Paste")
			(net "M_J_DQ<62>")
		)
		(pad "281" smd rect
			(at 4.59994 120.700038 90)
			(size 1.8034 0.508)
			(layers "F.Cu" "F.Mask" "F.Paste")
			(net "GND")
		)
		(pad "282" smd rect
			(at 4.59994 121.549922 90)
			(size 1.8034 0.508)
			(layers "F.Cu" "F.Mask" "F.Paste")
			(net "M_J_DQ<58>")
		)
		(pad "283" smd rect
			(at 4.59994 122.40006 90)
			(size 1.8034 0.508)
			(layers "F.Cu" "F.Mask" "F.Paste")
			(net "GND")
		)
		(pad "284" smd rect
			(at 4.59994 123.249944 90)
			(size 1.8034 0.508)
			(layers "F.Cu" "F.Mask" "F.Paste")
			(net "PVPP_GHJ")
		)
		(pad "285" smd rect
			(at 4.59994 124.100082 90)
			(size 1.8034 0.508)
			(layers "F.Cu" "F.Mask" "F.Paste")
			(net "SMB_DDR_GHJ_VPP_SDA")
		)
		(pad "286" smd rect
			(at 4.59994 124.949966 90)
			(size 1.8034 0.508)
			(layers "F.Cu" "F.Mask" "F.Paste")
			(net "PVPP_GHJ")
		)
		(pad "287" smd rect
			(at 4.59994 125.800104 90)
			(size 1.8034 0.508)
			(layers "F.Cu" "F.Mask" "F.Paste")
			(net "PVPP_GHJ")
		)
		(pad "288" smd rect
			(at 4.59994 126.649988 90)
			(size 1.8034 0.508)
			(layers "F.Cu" "F.Mask" "F.Paste")
			(net "PVPP_GHJ")
		)
	)
)
